(kicad_pcb
	(version 20221018)
	(generator pcbnew)
	(general
    (thickness 1.7403)
  )
	(paper "A4")
	(title_block
    (title "Data Center RDIMM DDR4 Tester")
    (date "2024-09-30")
    (rev "1.2.4")
		(comment 9 "footprints 285-292 of 690")
	)
	(layers
    (0 "F.Cu" signal)
    (1 "In1.Cu" power)
    (2 "In2.Cu" signal)
    (3 "In3.Cu" power)
    (4 "In4.Cu" power)
    (5 "In5.Cu" signal)
    (6 "In6.Cu" power)
    (7 "In7.Cu" signal)
    (8 "In8.Cu" power)
    (9 "In9.Cu" signal)
    (10 "In10.Cu" power)
    (31 "B.Cu" signal)
    (32 "B.Adhes" user "B.Adhesive")
    (33 "F.Adhes" user "F.Adhesive")
    (34 "B.Paste" user)
    (35 "F.Paste" user)
    (36 "B.SilkS" user "B.Silkscreen")
    (37 "F.SilkS" user "F.Silkscreen")
    (38 "B.Mask" user)
    (39 "F.Mask" user)
    (40 "Dwgs.User" user "User.Drawings")
    (41 "Cmts.User" user "User.Comments")
    (42 "Eco1.User" user "User.Eco1")
    (43 "Eco2.User" user "User.Eco2")
    (44 "Edge.Cuts" user)
    (45 "Margin" user)
    (46 "B.CrtYd" user "B.Courtyard")
    (47 "F.CrtYd" user "F.Courtyard")
    (48 "B.Fab" user)
    (49 "F.Fab" user)
  )
	(footprint "data-center-rdimm-ddr4-tester-footprints:SOT-23-3" (layer "F.Cu")
    (at 235.7 123.3)
    (property "Author" "Antmicro")
    (property "License" "Apache-2.0")
    (property "MPN" "BZX84C5V1-TP")
    (property "Manufacturer" "Micro Commercial Co")
    (property "Sheetfile" "supply.kicad_sch")
    (property "Sheetname" "Supply")
    (property "ki_description" "DIODE ZENER 5.1V 350MW SOT23")
    (attr smd)
    (fp_text reference "D19" (at -1.55 2.51) (layer "F.SilkS")
        (effects (font (size 0.7 0.7) (thickness 0.15)) (justify left bottom))
    )
    (fp_text value "BZX84C5V1-TP" (at -1.9 2.7) (layer "F.Fab") hide
        (effects (font (size 0.7 0.7) (thickness 0.15)) (justify left bottom))
    )
    (fp_text user "Author: Antmicro" (at -1.837 5.3) (layer "F.Fab") hide
        (effects (font (size 0.7 0.7) (thickness 0.15)) (justify left bottom))
    )
    (fp_text user "${REFERENCE}" (at -1.837 4) (layer "F.Fab") hide
        (effects (font (size 0.7 0.7) (thickness 0.15)) (justify left bottom))
    )
    (fp_text user "License: Apache-2.0" (at -1.8 6.8) (layer "F.Fab") hide
        (effects (font (size 0.7 0.7) (thickness 0.15)) (justify left bottom))
    )
    (fp_line (start -1.45 -1.35) (end -0.85 -1.35)
      (stroke (width 0.15) (type solid)) (layer "F.SilkS"))
    (fp_line (start -0.85 -1.35) (end -0.7 -1.5)
      (stroke (width 0.15) (type solid)) (layer "F.SilkS"))
    (fp_line (start -0.7 1.5) (end -0.7 1.35)
      (stroke (width 0.15) (type solid)) (layer "F.SilkS"))
    (fp_line (start 0.7 -1.5) (end -0.7 -1.5)
      (stroke (width 0.15) (type solid)) (layer "F.SilkS"))
    (fp_line (start 0.7 -0.4) (end 0.7 -1.5)
      (stroke (width 0.15) (type solid)) (layer "F.SilkS"))
    (fp_line (start 0.7 0.4) (end 0.7 1.5)
      (stroke (width 0.15) (type solid)) (layer "F.SilkS"))
    (fp_line (start 0.7 1.5) (end -0.7 1.5)
      (stroke (width 0.15) (type solid)) (layer "F.SilkS"))
    (fp_line (start -1.75 -0.5) (end -1.75 -1.4)
      (stroke (width 0.05) (type solid)) (layer "F.CrtYd"))
    (fp_line (start -1.75 0.5) (end -0.85 0.5)
      (stroke (width 0.05) (type solid)) (layer "F.CrtYd"))
    (fp_line (start -1.75 1.4) (end -1.75 0.5)
      (stroke (width 0.05) (type solid)) (layer "F.CrtYd"))
    (fp_line (start -0.9 -1.6) (end -0.9 -1.4)
      (stroke (width 0.05) (type solid)) (layer "F.CrtYd"))
    (fp_line (start -0.9 -1.6) (end 0.825 -1.6)
      (stroke (width 0.05) (type solid)) (layer "F.CrtYd"))
    (fp_line (start -0.9 -1.4) (end -1.75 -1.4)
      (stroke (width 0.05) (type solid)) (layer "F.CrtYd"))
    (fp_line (start -0.85 -0.5) (end -1.75 -0.5)
      (stroke (width 0.05) (type solid)) (layer "F.CrtYd"))
    (fp_line (start -0.85 0.5) (end -0.85 -0.5)
      (stroke (width 0.05) (type solid)) (layer "F.CrtYd"))
    (fp_line (start -0.85 1.4) (end -1.75 1.4)
      (stroke (width 0.05) (type solid)) (layer "F.CrtYd"))
    (fp_line (start -0.85 1.65) (end -0.85 1.4)
      (stroke (width 0.05) (type solid)) (layer "F.CrtYd"))
    (fp_line (start 0.825 -1.6) (end 0.825 -0.45)
      (stroke (width 0.05) (type solid)) (layer "F.CrtYd"))
    (fp_line (start 0.825 -0.45) (end 1.75 -0.45)
      (stroke (width 0.05) (type solid)) (layer "F.CrtYd"))
    (fp_line (start 0.85 0.45) (end 0.85 1.65)
      (stroke (width 0.05) (type solid)) (layer "F.CrtYd"))
    (fp_line (start 0.85 1.65) (end -0.85 1.65)
      (stroke (width 0.05) (type solid)) (layer "F.CrtYd"))
    (fp_line (start 1.75 -0.45) (end 1.75 0.45)
      (stroke (width 0.05) (type solid)) (layer "F.CrtYd"))
    (fp_line (start 1.75 0.45) (end 0.85 0.45)
      (stroke (width 0.05) (type solid)) (layer "F.CrtYd"))
    (fp_line (start -0.712 -1.325) (end -0.712 1.523)
      (stroke (width 0.15) (type solid)) (layer "F.Fab"))
    (fp_line (start -0.712 1.519) (end 0.688 1.519)
      (stroke (width 0.15) (type solid)) (layer "F.Fab"))
    (fp_line (start -0.437 -1.526) (end -0.712 -1.325)
      (stroke (width 0.15) (type solid)) (layer "F.Fab"))
    (fp_line (start -0.437 -1.526) (end 0.688 -1.526)
      (stroke (width 0.15) (type solid)) (layer "F.Fab"))
    (fp_line (start 0.688 1.519) (end 0.688 -1.52)
      (stroke (width 0.15) (type solid)) (layer "F.Fab"))
    (pad "1" smd roundrect (at -1.1 -0.951) (size 1 0.6) (layers "F.Cu" "F.Paste" "F.Mask") (roundrect_rratio 0.15)
      (net 9 "GND") (pinfunction "1") (pintype "passive"))
    (pad "2" smd roundrect (at -1.1 0.949) (size 1 0.6) (layers "F.Cu" "F.Paste" "F.Mask") (roundrect_rratio 0.15)
      (net 623 "unconnected-(D19-Pad2)") (pinfunction "2") (pintype "no_connect"))
    (pad "3" smd roundrect (at 1.1 -0.0005) (size 1 0.6) (layers "F.Cu" "F.Paste" "F.Mask") (roundrect_rratio 0.15)
      (net 108 "Net-(U27-~{OE})") (pinfunction "3") (pintype "passive"))
  )
	(footprint "data-center-rdimm-ddr4-tester-footprints:C_0402_1005Metric" (layer "F.Cu")
    (at 159.4 108.8 90)
    (descr "Capacitor SMD 0402")
    (tags "capacitor SMD 0402")
    (property "Author" "Antmicro")
    (property "DNP" "DNP")
    (property "Dielectric" "X5R")
    (property "License" "Apache-2.0")
    (property "MPN" "GRM155R61H104KE14D")
    (property "Manufacturer" "Murata")
    (property "Sheetfile" "ethernet.kicad_sch")
    (property "Sheetname" "Ethernet")
    (property "Val" "100n")
    (property "Voltage" "50V")
    (property "dnp" "")
    (property "exclude_from_bom" "")
    (property "ki_description" " ")
    (attr exclude_from_pos_files exclude_from_bom)
    (fp_text reference "C287" (at -3.72 0.42 90) (layer "F.SilkS")
        (effects (font (size 0.7 0.7) (thickness 0.15)) (justify left bottom))
    )
    (fp_text value "C_100n_0402" (at 0 1.4 90) (layer "F.Fab") hide
        (effects (font (size 0.7 0.7) (thickness 0.15)) (justify left bottom))
    )
    (fp_text user "Author: Antmicro" (at -0.932 4.17 90) (layer "F.Fab") hide
        (effects (font (size 0.7 0.7) (thickness 0.15)) (justify left bottom))
    )
    (fp_text user "License: Apache-2.0" (at -0.932 5.17 90) (layer "F.Fab") hide
        (effects (font (size 0.7 0.7) (thickness 0.15)) (justify left bottom))
    )
    (fp_text user "${REFERENCE}" (at -0.932 3.168 90) (layer "F.Fab") hide
        (effects (font (size 0.7 0.7) (thickness 0.15)) (justify left bottom))
    )
    (fp_rect (start -0.94 -0.47) (end 0.94 0.47)
      (stroke (width 0.05) (type solid)) (fill none) (layer "F.CrtYd"))
    (fp_rect (start -0.499 -0.249) (end 0.499 0.249)
      (stroke (width 0.15) (type solid)) (fill none) (layer "F.Fab"))
    (pad "1" smd roundrect (at -0.484 0 90) (size 0.59 0.64) (layers "F.Cu" "F.Paste" "F.Mask") (roundrect_rratio 0.25)
      (net 143 "3V3_SYS") (pintype "passive"))
    (pad "2" smd roundrect (at 0.484 0 90) (size 0.59 0.64) (layers "F.Cu" "F.Paste" "F.Mask") (roundrect_rratio 0.25)
      (net 9 "GND") (pintype "passive"))
  )
	(footprint "data-center-rdimm-ddr4-tester-footprints:C_0402_1005Metric" (layer "F.Cu")
    (at 110.883 110.6 180)
    (descr "Capacitor SMD 0402")
    (tags "capacitor SMD 0402")
    (property "Author" "Antmicro")
    (property "Dielectric" "X5R")
    (property "License" "Apache-2.0")
    (property "MPN" "GRM155R61H104KE14D")
    (property "Manufacturer" "Murata")
    (property "Sheetfile" "supply.kicad_sch")
    (property "Sheetname" "Supply")
    (property "Val" "100n")
    (property "Voltage" "50V")
    (property "ki_description" " ")
    (attr smd)
    (fp_text reference "C30" (at 3.043 0 180) (layer "F.SilkS")
        (effects (font (size 0.7 0.7) (thickness 0.15)) (justify left bottom))
    )
    (fp_text value "C_100n_0402" (at 0 1.4 180) (layer "F.Fab") hide
        (effects (font (size 0.7 0.7) (thickness 0.15)) (justify left bottom))
    )
    (fp_text user "License: Apache-2.0" (at -0.932 5.17 180) (layer "F.Fab") hide
        (effects (font (size 0.7 0.7) (thickness 0.15)) (justify left bottom))
    )
    (fp_text user "Author: Antmicro" (at -0.932 4.17 180) (layer "F.Fab") hide
        (effects (font (size 0.7 0.7) (thickness 0.15)) (justify left bottom))
    )
    (fp_text user "${REFERENCE}" (at -0.932 3.168 180) (layer "F.Fab") hide
        (effects (font (size 0.7 0.7) (thickness 0.15)) (justify left bottom))
    )
    (fp_rect (start -0.94 -0.47) (end 0.94 0.47)
      (stroke (width 0.05) (type solid)) (fill none) (layer "F.CrtYd"))
    (fp_rect (start -0.499 -0.249) (end 0.499 0.249)
      (stroke (width 0.15) (type solid)) (fill none) (layer "F.Fab"))
    (pad "1" smd roundrect (at -0.484 0 180) (size 0.59 0.64) (layers "F.Cu" "F.Paste" "F.Mask") (roundrect_rratio 0.25)
      (net 103 "VIN") (pintype "passive"))
    (pad "2" smd roundrect (at 0.484 0 180) (size 0.59 0.64) (layers "F.Cu" "F.Paste" "F.Mask") (roundrect_rratio 0.25)
      (net 9 "GND") (pintype "passive"))
  )
	(footprint "data-center-rdimm-ddr4-tester-footprints:C_0402_1005Metric" (layer "F.Cu")
    (at 256.18 79.181 180)
    (descr "Capacitor SMD 0402")
    (tags "capacitor SMD 0402")
    (property "Author" "Antmicro")
    (property "Dielectric" "X5R")
    (property "License" "Apache-2.0")
    (property "MPN" "GRM155R61H104KE14D")
    (property "Manufacturer" "Murata")
    (property "Sheetfile" "fmc_hpc.kicad_sch")
    (property "Sheetname" "FMC HPC")
    (property "Val" "100n")
    (property "Voltage" "50V")
    (property "ki_description" " ")
    (attr smd)
    (fp_text reference "C272" (at -0.74 -0.409 180) (layer "F.SilkS")
        (effects (font (size 0.7 0.7) (thickness 0.15)) (justify left bottom))
    )
    (fp_text value "C_100n_0402" (at 0 1.4 180) (layer "F.Fab") hide
        (effects (font (size 0.7 0.7) (thickness 0.15)) (justify left bottom))
    )
    (fp_text user "Author: Antmicro" (at -0.932 4.17 180) (layer "F.Fab") hide
        (effects (font (size 0.7 0.7) (thickness 0.15)) (justify left bottom))
    )
    (fp_text user "${REFERENCE}" (at -0.932 3.168 180) (layer "F.Fab") hide
        (effects (font (size 0.7 0.7) (thickness 0.15)) (justify left bottom))
    )
    (fp_text user "License: Apache-2.0" (at -0.932 5.17 180) (layer "F.Fab") hide
        (effects (font (size 0.7 0.7) (thickness 0.15)) (justify left bottom))
    )
    (fp_rect (start -0.94 -0.47) (end 0.94 0.47)
      (stroke (width 0.05) (type solid)) (fill none) (layer "F.CrtYd"))
    (fp_rect (start -0.499 -0.249) (end 0.499 0.249)
      (stroke (width 0.15) (type solid)) (fill none) (layer "F.Fab"))
    (pad "1" smd roundrect (at -0.484 0 180) (size 0.59 0.64) (layers "F.Cu" "F.Paste" "F.Mask") (roundrect_rratio 0.25)
      (net 512 "GTX_TX6_N") (pintype "passive"))
    (pad "2" smd roundrect (at 0.484 0 180) (size 0.59 0.64) (layers "F.Cu" "F.Paste" "F.Mask") (roundrect_rratio 0.25)
      (net 499 "/FMC HPC/GTX_TX6_C_N") (pintype "passive"))
  )
	(footprint "data-center-rdimm-ddr4-tester-footprints:C_0402_1005Metric" (layer "F.Cu")
    (at 254.71 97.955 180)
    (descr "Capacitor SMD 0402")
    (tags "capacitor SMD 0402")
    (property "Author" "Antmicro")
    (property "Dielectric" "X5R")
    (property "License" "Apache-2.0")
    (property "MPN" "GRM155R61H104KE14D")
    (property "Manufacturer" "Murata")
    (property "Sheetfile" "fmc_hpc.kicad_sch")
    (property "Sheetname" "FMC HPC")
    (property "Val" "100n")
    (property "Voltage" "50V")
    (property "ki_description" " ")
    (attr smd)
    (fp_text reference "C261" (at 3.64 -0.365 180) (layer "F.SilkS")
        (effects (font (size 0.7 0.7) (thickness 0.15)) (justify left bottom))
    )
    (fp_text value "C_100n_0402" (at 0 1.4 180) (layer "F.Fab") hide
        (effects (font (size 0.7 0.7) (thickness 0.15)) (justify left bottom))
    )
    (fp_text user "License: Apache-2.0" (at -0.932 5.17 180) (layer "F.Fab") hide
        (effects (font (size 0.7 0.7) (thickness 0.15)) (justify left bottom))
    )
    (fp_text user "Author: Antmicro" (at -0.932 4.17 180) (layer "F.Fab") hide
        (effects (font (size 0.7 0.7) (thickness 0.15)) (justify left bottom))
    )
    (fp_text user "${REFERENCE}" (at -0.932 3.168 180) (layer "F.Fab") hide
        (effects (font (size 0.7 0.7) (thickness 0.15)) (justify left bottom))
    )
    (fp_rect (start -0.94 -0.47) (end 0.94 0.47)
      (stroke (width 0.05) (type solid)) (fill none) (layer "F.CrtYd"))
    (fp_rect (start -0.499 -0.249) (end 0.499 0.249)
      (stroke (width 0.15) (type solid)) (fill none) (layer "F.Fab"))
    (pad "1" smd roundrect (at -0.484 0 180) (size 0.59 0.64) (layers "F.Cu" "F.Paste" "F.Mask") (roundrect_rratio 0.25)
      (net 419 "/FMC HPC/GTX_TX1_C_P") (pintype "passive"))
    (pad "2" smd roundrect (at 0.484 0 180) (size 0.59 0.64) (layers "F.Cu" "F.Paste" "F.Mask") (roundrect_rratio 0.25)
      (net 420 "GTX_TX1_P") (pintype "passive"))
  )
	(footprint "data-center-rdimm-ddr4-tester-footprints:R_0201" (layer "F.Cu")
    (at 159.575 104.3 -90)
    (descr "Resistor SMD 0201")
    (tags "resistor SMD 0201")
    (property "Author" "Antmicro")
    (property "License" "Apache-2.0")
    (property "MPN" "CR0201-FX-0R00GLF")
    (property "Manufacturer" "Bourns")
    (property "Sheetfile" "ethernet.kicad_sch")
    (property "Sheetname" "Ethernet")
    (property "Tolerance" "1%")
    (property "Val" "0R")
    (property "ki_description" "0R resistor in 0201 package with 1% tolerance")
    (attr smd)
    (fp_text reference "R101" (at -0.65 -0.175 -90) (layer "F.SilkS")
        (effects (font (size 0.7 0.7) (thickness 0.15)) (justify left bottom))
    )
    (fp_text value "R_0R_0201" (at 0 1.25 -90) (layer "F.Fab") hide
        (effects (font (size 0.7 0.7) (thickness 0.15)) (justify left bottom))
    )
    (fp_text user "${REFERENCE}" (at -0.71 3.25 -90) (layer "F.Fab") hide
        (effects (font (size 0.7 0.7) (thickness 0.15)) (justify left bottom))
    )
    (fp_text user "License: Apache-2.0" (at -0.71 4.25 -90) (layer "F.Fab") hide
        (effects (font (size 0.7 0.7) (thickness 0.15)) (justify left bottom))
    )
    (fp_text user "Author: Antmicro" (at -0.71 5.25 -90) (layer "F.Fab") hide
        (effects (font (size 0.7 0.7) (thickness 0.15)) (justify left bottom))
    )
    (fp_rect (start -0.71 -0.36) (end 0.71 0.36)
      (stroke (width 0.05) (type solid)) (fill none) (layer "F.CrtYd"))
    (fp_rect (start -0.3 -0.15) (end 0.298 0.148)
      (stroke (width 0.15) (type solid)) (fill none) (layer "F.Fab"))
    (pad "" smd roundrect (at -0.346 0 270) (size 0.318 0.36) (layers "F.Paste") (roundrect_rratio 0.25))
    (pad "" smd roundrect (at 0.344 0 270) (size 0.318 0.36) (layers "F.Paste") (roundrect_rratio 0.25))
    (pad "1" smd roundrect (at -0.32 0 270) (size 0.46 0.4) (layers "F.Cu" "F.Mask") (roundrect_rratio 0.25)
      (net 168 "/Ethernet/ETH3_P") (pintype "passive"))
    (pad "2" smd roundrect (at 0.32 0 270) (size 0.46 0.4) (layers "F.Cu" "F.Mask") (roundrect_rratio 0.25)
      (net 828 "/Ethernet/ETH3_BP_P") (pintype "passive"))
  )
	(footprint "data-center-rdimm-ddr4-tester-footprints:Fiducial_1mm_Mask2mm" (layer "F.Cu")
    (at 110.15 128)
    (descr "Circular Fiducial, 1mm bare copper, 3mm soldermask opening")
    (tags "fiducial")
    (property "Author" "Antmicro")
    (property "License" "Apache-2.0")
    (property "MPN" "")
    (property "Manufacturer" "")
    (property "Sheetfile" "data-center-rdimm-ddr4-tester.kicad_sch")
    (property "Sheetname" "")
    (property "exclude_from_bom" "")
    (property "ki_description" "Fiducial Marker for use with single board only")
    (attr exclude_from_pos_files exclude_from_bom)
    (fp_text reference "FID2" (at 2.44 1.09 90) (layer "F.SilkS")
        (effects (font (size 0.7 0.7) (thickness 0.15)) (justify left bottom))
    )
    (fp_text value "Fiducial_1mm_Mask2mm" (at 0 2.2) (layer "F.Fab")
        (effects (font (size 0.7 0.7) (thickness 0.15)) (justify left bottom))
    )
    (fp_text user "${REFERENCE}" (at -1.25 4.603) (layer "F.Fab") hide
        (effects (font (size 0.7 0.7) (thickness 0.15)) (justify left bottom))
    )
    (fp_text user "License: Apache-2.0" (at -1.25 7.003) (layer "F.Fab") hide
        (effects (font (size 0.7 0.7) (thickness 0.15)) (justify left bottom))
    )
    (fp_text user "Author: Antmicro" (at -1.25 5.803) (layer "F.Fab") hide
        (effects (font (size 0.7 0.7) (thickness 0.15)) (justify left bottom))
    )
    (fp_circle (center 0 0) (end 1.24 0)
      (stroke (width 0.05) (type solid)) (fill none) (layer "F.CrtYd"))
    (fp_circle (center 0 0) (end 0.999 0)
      (stroke (width 0.15) (type solid)) (fill none) (layer "F.Fab"))
    (pad "" smd circle (at 0 0) (size 1 1) (layers "F.Cu" "F.Mask")
      (solder_mask_margin 0.5) (clearance 0.5))
  )
	(footprint "data-center-rdimm-ddr4-tester-footprints:R_0402_1005Metric" (layer "F.Cu")
    (at 250.9 119.815 180)
    (descr "Resistor SMD 0402")
    (tags "resistor SMD 0402")
    (property "Author" "Antmicro")
    (property "License" "Apache-2.0")
    (property "MPN" "CR0402-FX-33R0GLF")
    (property "Manufacturer" "Bourns")
    (property "Sheetfile" "fmc_hpc.kicad_sch")
    (property "Sheetname" "FMC HPC")
    (property "Tolerance" "1%")
    (property "Val" "33R")
    (property "ki_description" "33R resistor in 0402 package with 1% tolerance")
    (attr smd)
    (fp_text reference "R211" (at 1.03 1.565 180) (layer "F.SilkS")
        (effects (font (size 0.7 0.7) (thickness 0.15)) (justify left bottom))
    )
    (fp_text value "R_33R_0402" (at 0 1.4 180) (layer "F.Fab") hide
        (effects (font (size 0.7 0.7) (thickness 0.15)) (justify left bottom))
    )
    (fp_text user "License: Apache-2.0" (at -0.95 5.169 180) (layer "F.Fab") hide
        (effects (font (size 0.7 0.7) (thickness 0.15)) (justify left bottom))
    )
    (fp_text user "${REFERENCE}" (at -0.95 3.168 180) (layer "F.Fab") hide
        (effects (font (size 0.7 0.7) (thickness 0.15)) (justify left bottom))
    )
    (fp_text user "Author: Antmicro" (at -0.95 4.169 180) (layer "F.Fab") hide
        (effects (font (size 0.7 0.7) (thickness 0.15)) (justify left bottom))
    )
    (fp_rect (start -0.93 -0.47) (end 0.93 0.47)
      (stroke (width 0.05) (type solid)) (fill none) (layer "F.CrtYd"))
    (fp_rect (start -0.5 -0.25) (end 0.5 0.25)
      (stroke (width 0.15) (type solid)) (fill none) (layer "F.Fab"))
    (pad "1" smd roundrect (at -0.485 0 180) (size 0.59 0.64) (layers "F.Cu" "F.Paste" "F.Mask") (roundrect_rratio 0.25)
      (net 669 "/FMC HPC/GTR_REFCLK0_R_N") (pintype "passive"))
    (pad "2" smd roundrect (at 0.485 0 180) (size 0.59 0.64) (layers "F.Cu" "F.Paste" "F.Mask") (roundrect_rratio 0.25)
      (net 408 "GTR_REFCLK0_C_N") (pintype "passive"))
  )
)
